FILE_TYPE = CONNECTIVITY;
{Allegro Design Entry HDL 16.6-p007 (v16-6-112F) 10/10/2012}
"PAGE_NUMBER" = 108;
0"NC";
1"P3E_CPU0_PE1_PCH_CON_TXN<15:8>";
2"P3E_CPU0_PE1_PCH_CON_RXP<15:8>";
3"P3E_CPU0_PE1_PCH_CON_TXP<15:8>";
4"P3E_CPU0_PE1_PCH_CON_RXN<15:8>";
5"P12V\g";
6"P12V\g";
7"GND\g";
8"P3V3\g";
9"GND\g";
10"P3V3\g";
11"GND\g";
12"P3V3\g";
13"GND\g";
14"P3V3_STBY\g";
15"GND\g";
16"P3V3_STBY\g";
17"P3V3\g";
18"P12V\g";
19"P3E_CPU0_PE1_PCH_CON_RXN<8>";
20"P3E_CPU0_PE1_PCH_CON_RXN<9>";
21"P3E_CPU0_PE1_PCH_CON_RXP<9>";
22"P3E_CPU0_PE1_PCH_CON_RXN<10>";
23"P3E_CPU0_PE1_PCH_CON_RXN<11>";
24"P3E_CPU0_PE1_PCH_CON_RXP<12>";
25"P3E_CPU0_PE1_PCH_CON_RXN<12>";
26"FM_PRSNT_2_5_N";
27"P3E_CPU0_PE1_PCH_CON_RXN<14>";
28"P3E_CPU0_PE1_PCH_CON_RXP<13>";
29"P3E_CPU0_PE1_PCH_CON_RXP<14>";
30"P3E_CPU0_PE1_PCH_CON_RXP<15>";
31"P3E_CPU0_PE1_PCH_CON_RXN<15>";
32"P3E_CPU0_PE1_PCH_CON_TXP<8>";
33"P3E_CPU0_PE1_PCH_CON_TXP<9>";
34"P3E_CPU0_PE1_PCH_CON_TXP<10>";
35"P3E_CPU0_PE1_PCH_CON_TXP<11>";
36"P3E_CPU0_PE1_PCH_CON_TXP<12>";
37"FM_PRSNT_2_4_N";
38"P3E_CPU0_PE1_PCH_CON_TXP<14>";
39"P3E_CPU0_PE1_PCH_CON_TXP<15>";
40"P3E_CPU0_PE1_PCH_CON_TXN<14>";
41"CLK_100M_PCH_SLOTX24_S3_DN";
42"CLK_100M_PCH_SLOTX24_S3_DP";
43"CLK_100M_PCH_SLOTX24_S0_DN";
44"CLK_100M_PCH_SLOTX24_S0_DP";
45"CLK_100M_PCH_SLOTX24_S5_DN";
46"CLK_100M_PCH_SLOTX24_S5_DP";
47"CLK_100M_PCH_SLOTX24_S2_DN";
48"CLK_100M_PCH_SLOTX24_S2_DP";
49"P3E_CPU0_PE1_PCH_CON_RXP<10>";
50"P3E_CPU0_PE1_PCH_CON_TXN<13>";
51"P3E_CPU0_PE1_PCH_CON_TXP<13>";
52"P3E_CPU0_PE1_PCH_CON_TXN<12>";
53"P3E_CPU0_PE1_PCH_CON_RXN<13>";
54"CLK_100M_PCH_SLOTX24_S1_DN";
55"CLK_100M_PCH_SLOTX24_S4_DP";
56"FM_PRSNT_2_3_N";
57"FM_PRSNT_2_2_N";
58"RST_PCIE_RISER1_PERST_R_N";
59"FM_PE_SLOTX24_WAKE_N";
60"FM_PRSNT_2_1_N";
61"FM_SLT_CFG0";
62"IRQ_OOB_MGMT_RISER_ALERT_N";
63"CLK_100M_PCH_SLOTX24_S4_DN";
64"FM_SLT_CFG1";
65"FM_PWRBRK_SLOT_N";
66"P3E_CPU0_PE1_PCH_CON_RXP<11>";
67"P3E_CPU0_PE1_PCH_CON_TXN<8>";
68"P3E_CPU0_PE1_PCH_CON_TXN<9>";
69"P3E_CPU0_PE1_PCH_CON_TXN<10>";
70"P3E_CPU0_PE1_PCH_CON_TXN<11>";
71"P3E_CPU0_PE1_PCH_CON_TXN<15>";
72"CLK_100M_PCH_SLOTX24_S1_DP";
73"SMB_SLOTX24_STBY_LVC3_SDA_R2";
74"SMB_SLOTX24_STBY_LVC3_SCL_R2";
75"RST_PCIE_RISER1_PERST_N";
76"FM_PWRBRK_N";
77"SMB_SLOTX24_STBY_LVC3_SCL_R2";
78"SMB_SLOTX24_STBY_LVC3_SDA_R2";
79"SMB_SLOTX24_PCH_STBY_LVC3_SCL";
80"SMB_SLOTX24_BMC_STBY_LVC3_SCL";
81"SMB_SLOTX24_BMC_STBY_LVC3_SDA";
82"SMB_SLOTX24_PCH_STBY_LVC3_SDA";
%"CAP_A"
"1","(-3275,675)","0","dev_discrete","I1";
;
CDS_LIB"dev_discrete"
CDS_SEC"1"
CDS_LOCATION"C2U20"
SEC"1"
SEC_TYPE"0402V"
ROOM"IO_SLOT"
PACK_TYPE"0402V"
MATERIAL"X7R"
VOLTAGE"16V"
TOLERANCE"10%"
VALUE"0.1UF"
LOCATION"C2U20"
PART_NUMBER"A36096-030";
"B"
$PN"2"11;
"A"
$PN"1"18;
%"P12V"
"1","(1375,4675)","0","mstr_symbols","I165";
;
HDL_POWER"P12V"
SIZE"1B"
CDS_LIB"mstr_symbols"
BODY_TYPE"PLUMBING"
VOLTAGE"+12.";
"G\NAC"5;
%"P12V"
"1","(-350,4725)","0","mstr_symbols","I167";
;
HDL_POWER"P12V"
BODY_TYPE"PLUMBING"
CDS_LIB"mstr_symbols"
SIZE"1B"
VOLTAGE"+12.";
"G\NAC"6;
%"GND"
"1","(-100,1225)","0","mstr_symbols","I168";
;
VOLTAGE"0"
CDS_LIB"mstr_symbols"
SIZE"1B"
BODY_TYPE"PLUMBING"
HDL_POWER"GND";
"A\NAC"7;
%"P3V3"
"1","(-525,4625)","0","mstr_symbols","I172";
;
HDL_POWER"P3V3"
BODY_TYPE"PLUMBING"
CDS_LIB"mstr_symbols"
VOLTAGE"3.3V"
SIZE"1B";
"G\NAC"8;
%"RES"
"1","(-625,3625)","0","mstr_discrete","I173";
;
CDS_SEC"1"
CDS_LOCATION"R2U37"
CDS_LIB"mstr_discrete"
ROOM"IO_SLOT"
SEC"1"
SEC_TYPE"0402"
TOLERANCE"5%"
LOCATION"R2U37"
MATERIAL"CHIP"
PACK_TYPE"0402"
WATTAGE"1/16W"
VALUE"0.0"
PART_NUMBER"G21497-005";
"B"
$PN"2"58;
"A"
$PN"1"75;
%"CAP_A"
"1","(-2875,650)","0","dev_discrete","I2";
;
CDS_LIB"dev_discrete"
CDS_LOCATION"C2U24"
SEC"1"
SEC_TYPE"0402V"
CDS_SEC"1"
ROOM"IO_SLOT"
PACK_TYPE"0402V"
MATERIAL"X7R"
VOLTAGE"16V"
TOLERANCE"10%"
VALUE"0.1UF"
LOCATION"C2U24"
PART_NUMBER"A36096-030";
"B"
$PN"2"11;
"A"
$PN"1"18;
%"GND"
"1","(1050,1225)","0","mstr_symbols","I236";
;
BODY_TYPE"PLUMBING"
HDL_POWER"GND"
CDS_LIB"mstr_symbols"
SIZE"1B"
VOLTAGE"0";
"A\NAC"9;
%"P3V3"
"1","(1600,4675)","0","mstr_symbols","I238";
;
HDL_POWER"P3V3"
BODY_TYPE"PLUMBING"
CDS_LIB"mstr_symbols"
SIZE"1B"
VOLTAGE"3.3V";
"G\NAC"10;
%"GND"
"1","(-2875,300)","0","mstr_symbols","I250";
;
BODY_TYPE"PLUMBING"
CDS_LIB"mstr_symbols"
VOLTAGE"0"
HDL_POWER"GND"
SIZE"1B";
"A\NAC"11;
%"P3V3"
"1","(-3275,1650)","0","mstr_symbols","I251";
;
HDL_POWER"P3V3"
VOLTAGE"3.3V"
BODY_TYPE"PLUMBING"
CDS_LIB"mstr_symbols"
SIZE"1B";
"G\NAC"12;
%"GND"
"1","(-2875,975)","0","mstr_symbols","I252";
;
BODY_TYPE"PLUMBING"
CDS_LIB"mstr_symbols"
VOLTAGE"0"
SIZE"1B"
HDL_POWER"GND";
"A\NAC"13;
%"SCONN200_H68296001"
"1","(500,3075)","0","mstr_sconn","I258";
;
CDS_SEC"1"
CDS_LIB"mstr_sconn"
CDS_LMAN_SYM_OUTLINE"-250,1350,250,-1350"
CDS_LOCATION"J8G1"
PACK_TYPE"SM"
ROOM"IO_SLOT"
SEC"1"
SEC_TYPE"SM"
PART_NUMBER"H68296-001"
LOCATION"J8G1"
MATERIAL"CONN";
"MH2"
$PN"MH2"9;
"IO98"
$PN"98"9;
"IO96"
$PN"96"20;
"IO94"
$PN"94"21;
"IO92"
$PN"92"9;
"IO90"
$PN"90"49;
"IO88"
$PN"88"22;
"MH1"
$PN"MH1"7;
"IO65"
$PN"65"7;
"IO67"
$PN"67"50;
"IO69"
$PN"69"51;
"IO100"
$PN"100"19;
"IO73"
$PN"73"52;
"IO99"
$PN"99"32;
"IO78"
$PN"78"24;
"IO74"
$PN"74"9;
"IO72"
$PN"72"28;
"IO71"
$PN"71"7;
"IO70"
$PN"70"53;
"IO68"
$PN"68"9;
"IO66"
$PN"66"26;
"IO64"
$PN"64"9;
"IO63"
$PN"63"37;
"IO62"
$PN"62"29;
"IO61"
$PN"61"7;
"IO60"
$PN"60"27;
"IO59"
$PN"59"40;
"IO58"
$PN"58"9;
"IO57"
$PN"57"38;
"IO56"
$PN"56"30;
"IO55"
$PN"55"7;
"IO54"
$PN"54"31;
"IO53"
$PN"53"39;
"IO52"
$PN"52"9;
"IO50"
$PN"50"47;
"IO48"
$PN"48"48;
"IO46"
$PN"46"9;
"IO45"
$PN"45"42;
"IO44"
$PN"44"54;
"IO43"
$PN"43"7;
"IO41"
$PN"41"43;
"IO40"
$PN"40"9;
"IO39"
$PN"39"44;
"IO37"
$PN"37"7;
"IO36"
$PN"36"55;
"IO35"
$PN"35"45;
"IO34"
$PN"34"9;
"IO33"
$PN"33"46;
"IO32"
$PN"32"56;
"IO31"
$PN"31"7;
"IO30"
$PN"30"57;
"IO29"
$PN"29"58;
"IO28"
$PN"28"59;
"IO27"
$PN"27"60;
"IO25"
$PN"25"14;
"IO23"
$PN"23"8;
"IO21"
$PN"21"8;
"IO19"
$PN"19"61;
"IO16"
$PN"16"62;
"IO14"
$PN"14"9;
"IO12"
$PN"12"5;
"IO10"
$PN"10"5;
"IO8"
$PN"8"5;
"IO6"
$PN"6"5;
"IO4"
$PN"4"5;
"IO2"
$PN"2"5;
"IO9"
$PN"9"6;
"IO38"
$PN"38"63;
"IO18"
$PN"18"64;
"IO20"
$PN"20"65;
"IO22"
$PN"22"10;
"IO24"
$PN"24"10;
"IO26"
$PN"26"9;
"IO7"
$PN"7"6;
"IO5"
$PN"5"6;
"IO3"
$PN"3"6;
"IO1"
$PN"1"6;
"IO76"
$PN"76"25;
"IO80"
$PN"80"9;
"IO75"
$PN"75"36;
"IO82"
$PN"82"23;
"IO84"
$PN"84"66;
"IO86"
$PN"86"9;
"IO77"
$PN"77"7;
"IO95"
$PN"95"7;
"IO97"
$PN"97"67;
"IO93"
$PN"93"33;
"IO91"
$PN"91"68;
"IO89"
$PN"89"7;
"IO87"
$PN"87"34;
"IO85"
$PN"85"69;
"IO83"
$PN"83"7;
"IO81"
$PN"81"35;
"IO79"
$PN"79"70;
"IO51"
$PN"51"71;
"IO49"
$PN"49"7;
"IO47"
$PN"47"41;
"IO42"
$PN"42"72;
"IO15"
$PN"15"73;
"IO17"
$PN"17"74;
"IO13"
$PN"13"7;
"IO11"
$PN"11"6;
%"P3V3_STBY"
"1","(-25,4625)","0","mstr_symbols","I262";
;
HDL_POWER"P3V3_STBY"
BODY_TYPE"PLUMBING"
VOLTAGE"3.3V"
CDS_LIB"mstr_symbols"
SIZE"1B";
"G\NAC"14;
%"TAP"
"1","(-550,3075)","2","mstr_standard","I271";
;
CDS_LIB"mstr_standard"
BODY_TYPE"PLUMBING"
HDL_TAP"TRUE";
"B \NAC \NWC"1;
"S \NAC"
BN"15"71;
%"TAP"
"1","(-750,3025)","2","mstr_standard","I272";
;
BODY_TYPE"PLUMBING"
CDS_LIB"mstr_standard"
HDL_TAP"TRUE";
"B \NAC \NWC"3;
"S \NAC"
BN"15"39;
%"TAP"
"1","(-750,2925)","2","mstr_standard","I273";
;
HDL_TAP"TRUE"
BODY_TYPE"PLUMBING"
CDS_LIB"mstr_standard";
"B \NAC \NWC"3;
"S \NAC"
BN"14"38;
%"TAP"
"1","(-550,2875)","2","mstr_standard","I274";
;
HDL_TAP"TRUE"
BODY_TYPE"PLUMBING"
CDS_LIB"mstr_standard";
"B \NAC \NWC"1;
"S \NAC"
BN"14"40;
%"TAP"
"1","(-750,2625)","2","mstr_standard","I275";
;
HDL_TAP"TRUE"
BODY_TYPE"PLUMBING"
CDS_LIB"mstr_standard";
"B \NAC \NWC"3;
"S \NAC"
BN"13"51;
%"TAP"
"1","(-550,2675)","2","mstr_standard","I276";
;
HDL_TAP"TRUE"
BODY_TYPE"PLUMBING"
CDS_LIB"mstr_standard";
"B \NAC \NWC"1;
"S \NAC"
BN"13"50;
%"TAP"
"1","(-750,2475)","2","mstr_standard","I277";
;
BODY_TYPE"PLUMBING"
CDS_LIB"mstr_standard"
HDL_TAP"TRUE";
"B \NAC \NWC"3;
"S \NAC"
BN"12"36;
%"TAP"
"1","(-550,2525)","2","mstr_standard","I278";
;
HDL_TAP"TRUE"
CDS_LIB"mstr_standard"
BODY_TYPE"PLUMBING";
"B \NAC \NWC"1;
"S \NAC"
BN"12"52;
%"TAP"
"1","(-750,2325)","2","mstr_standard","I279";
;
HDL_TAP"TRUE"
BODY_TYPE"PLUMBING"
CDS_LIB"mstr_standard";
"B \NAC \NWC"3;
"S \NAC"
BN"11"35;
%"TAP"
"1","(-550,2375)","2","mstr_standard","I280";
;
HDL_TAP"TRUE"
BODY_TYPE"PLUMBING"
CDS_LIB"mstr_standard";
"B \NAC \NWC"1;
"S \NAC"
BN"11"70;
%"TAP"
"1","(-750,2175)","2","mstr_standard","I281";
;
HDL_TAP"TRUE"
BODY_TYPE"PLUMBING"
CDS_LIB"mstr_standard";
"B \NAC \NWC"3;
"S \NAC"
BN"10"34;
%"TAP"
"1","(-550,2225)","2","mstr_standard","I282";
;
HDL_TAP"TRUE"
CDS_LIB"mstr_standard"
BODY_TYPE"PLUMBING";
"B \NAC \NWC"1;
"S \NAC"
BN"10"69;
%"TAP"
"1","(-750,2025)","2","mstr_standard","I283";
;
HDL_TAP"TRUE"
CDS_LIB"mstr_standard"
BODY_TYPE"PLUMBING";
"B \NAC \NWC"3;
"S \NAC"
BN"9"33;
%"TAP"
"1","(-550,2075)","2","mstr_standard","I284";
;
HDL_TAP"TRUE"
BODY_TYPE"PLUMBING"
CDS_LIB"mstr_standard";
"B \NAC \NWC"1;
"S \NAC"
BN"9"68;
%"TAP"
"1","(-750,1875)","2","mstr_standard","I285";
;
HDL_TAP"TRUE"
BODY_TYPE"PLUMBING"
CDS_LIB"mstr_standard";
"B \NAC \NWC"3;
"S \NAC"
BN"8"32;
%"TAP"
"1","(-550,1925)","2","mstr_standard","I286";
;
HDL_TAP"TRUE"
BODY_TYPE"PLUMBING"
CDS_LIB"mstr_standard";
"B \NAC \NWC"1;
"S \NAC"
BN"8"67;
%"TAP"
"1","(1350,2975)","0","mstr_standard","I295";
;
CDS_LIB"mstr_standard"
HDL_TAP"TRUE"
BODY_TYPE"PLUMBING";
"B \NAC \NWC"2;
"S \NAC"
BN"15"30;
%"TAP"
"1","(1500,3025)","0","mstr_standard","I296";
;
CDS_LIB"mstr_standard"
BODY_TYPE"PLUMBING"
HDL_TAP"TRUE";
"B \NAC \NWC"4;
"S \NAC"
BN"15"31;
%"TAP"
"1","(1500,2875)","0","mstr_standard","I297";
;
HDL_TAP"TRUE"
BODY_TYPE"PLUMBING"
CDS_LIB"mstr_standard";
"B \NAC \NWC"4;
"S \NAC"
BN"14"27;
%"TAP"
"1","(1350,2825)","0","mstr_standard","I298";
;
CDS_LIB"mstr_standard"
BODY_TYPE"PLUMBING"
HDL_TAP"TRUE";
"B \NAC \NWC"2;
"S \NAC"
BN"14"29;
%"TAP"
"1","(1500,2625)","0","mstr_standard","I299";
;
CDS_LIB"mstr_standard"
BODY_TYPE"PLUMBING"
HDL_TAP"TRUE";
"B \NAC \NWC"4;
"S \NAC"
BN"13"53;
%"TAP"
"1","(1350,2575)","0","mstr_standard","I300";
;
CDS_LIB"mstr_standard"
BODY_TYPE"PLUMBING"
HDL_TAP"TRUE";
"B \NAC \NWC"2;
"S \NAC"
BN"13"28;
%"TAP"
"1","(1500,2475)","0","mstr_standard","I301";
;
BODY_TYPE"PLUMBING"
CDS_LIB"mstr_standard"
HDL_TAP"TRUE";
"B \NAC \NWC"4;
"S \NAC"
BN"12"25;
%"TAP"
"1","(1350,2425)","0","mstr_standard","I302";
;
HDL_TAP"TRUE"
CDS_LIB"mstr_standard"
BODY_TYPE"PLUMBING";
"B \NAC \NWC"2;
"S \NAC"
BN"12"24;
%"TAP"
"1","(1500,2325)","0","mstr_standard","I303";
;
CDS_LIB"mstr_standard"
BODY_TYPE"PLUMBING"
HDL_TAP"TRUE";
"B \NAC \NWC"4;
"S \NAC"
BN"11"23;
%"TAP"
"1","(1350,2275)","0","mstr_standard","I304";
;
BODY_TYPE"PLUMBING"
CDS_LIB"mstr_standard"
HDL_TAP"TRUE";
"B \NAC \NWC"2;
"S \NAC"
BN"11"66;
%"TAP"
"1","(1500,2175)","0","mstr_standard","I305";
;
CDS_LIB"mstr_standard"
BODY_TYPE"PLUMBING"
HDL_TAP"TRUE";
"B \NAC \NWC"4;
"S \NAC"
BN"10"22;
%"TAP"
"1","(1350,2125)","0","mstr_standard","I306";
;
CDS_LIB"mstr_standard"
BODY_TYPE"PLUMBING"
HDL_TAP"TRUE";
"B \NAC \NWC"2;
"S \NAC"
BN"10"49;
%"TAP"
"1","(1500,1975)","0","mstr_standard","I307";
;
BODY_TYPE"PLUMBING"
HDL_TAP"TRUE"
CDS_LIB"mstr_standard";
"B \NAC \NWC"4;
"S \NAC"
BN"9"20;
%"TAP"
"1","(1350,2025)","0","mstr_standard","I308";
;
BODY_TYPE"PLUMBING"
CDS_LIB"mstr_standard"
HDL_TAP"TRUE";
"B \NAC \NWC"2;
"S \NAC"
BN"9"21;
%"CAP_A"
"1","(-1950,1350)","0","dev_discrete","I315";
;
CDS_LIB"dev_discrete"
CDS_LOCATION"C2U23"
CDS_SEC"1"
SEC"1"
SEC_TYPE"0402V"
ROOM"IO_SLOT"
MATERIAL"X7R"
TOLERANCE"10%"
VOLTAGE"16V"
PART_NUMBER"A36096-030"
VALUE"0.1UF"
PACK_TYPE"0402V"
LOCATION"C2U23";
"B"
$PN"2"15;
"A"
$PN"1"16;
%"GND"
"1","(-1950,950)","0","mstr_symbols","I316";
;
BODY_TYPE"PLUMBING"
CDS_LIB"mstr_symbols"
SIZE"1B"
VOLTAGE"0"
HDL_POWER"GND";
"A\NAC"15;
%"CAP_A"
"1","(-2350,1375)","0","dev_discrete","I318";
;
CDS_LIB"dev_discrete"
CDS_LOCATION"C2U22"
CDS_SEC"1"
ROOM"IO_SLOT"
SEC_TYPE"0402V"
SEC"1"
LOCATION"C2U22"
VALUE"0.1UF"
MATERIAL"X7R"
PART_NUMBER"A36096-030"
TOLERANCE"10%"
VOLTAGE"16V"
PACK_TYPE"0402V";
"B"
$PN"2"15;
"A"
$PN"1"16;
%"P3V3_STBY"
"1","(-2350,1625)","0","mstr_symbols","I319";
;
HDL_POWER"P3V3_STBY"
VOLTAGE"3.3V"
BODY_TYPE"PLUMBING"
SIZE"1B"
CDS_LIB"mstr_symbols";
"G\NAC"16;
%"RES"
"1","(-2400,4600)","0","mstr_discrete","I320";
;
CDS_LOCATION"R2U35"
WATTAGE"1/16W"
PACK_TYPE"0402"
CDS_LIB"mstr_discrete"
$SEC"1"
CDS_SEC"1"
ROOM"SMBUS"
SKU"A"
BOM_COST"SM_CONTROLLER"
LOCATION"R2U35"
VALUE"20.0"
TOLERANCE"1%"
PART_NUMBER"G21796-173"
MATERIAL"EMPTY";
"B"
$PN"2"78;
"A"
$PN"1"82;
%"RES"
"1","(-2400,4500)","0","mstr_discrete","I330";
;
CDS_LOCATION"R2U31"
WATTAGE"1/16W"
CDS_LIB"mstr_discrete"
PACK_TYPE"0402"
SKU"B"
ROOM"SMBUS"
$SEC"1"
CDS_SEC"1"
BOM_COST"SM_CONTROLLER"
LOCATION"R2U31"
VALUE"20.0"
TOLERANCE"1%"
MATERIAL"CHIP"
PART_NUMBER"G21796-173";
"B"
$PN"2"78;
"A"
$PN"1"81;
%"RES"
"1","(-2400,4250)","0","mstr_discrete","I339";
;
CDS_LOCATION"R2U32"
WATTAGE"1/16W"
CDS_LIB"mstr_discrete"
$SEC"1"
CDS_SEC"1"
PACK_TYPE"0402"
SKU"B"
ROOM"SMBUS"
BOM_COST"SM_CONTROLLER"
LOCATION"R2U32"
VALUE"20.0"
TOLERANCE"1%"
MATERIAL"CHIP"
PART_NUMBER"G21796-173";
"B"
$PN"2"77;
"A"
$PN"1"80;
%"RES"
"1","(-2400,4350)","0","mstr_discrete","I340";
;
CDS_LOCATION"R2U36"
WATTAGE"1/16W"
CDS_LIB"mstr_discrete"
CDS_SEC"1"
$SEC"1"
PACK_TYPE"0402"
BOM_COST"SM_CONTROLLER"
SKU"A"
ROOM"SMBUS"
LOCATION"R2U36"
VALUE"20.0"
TOLERANCE"1%"
PART_NUMBER"G21796-173"
MATERIAL"EMPTY";
"B"
$PN"2"77;
"A"
$PN"1"79;
%"RES"
"1","(2375,3775)","0","mstr_discrete","I341";
;
CDS_SEC"1"
CDS_LOCATION"R7E22"
CDS_LIB"mstr_discrete"
ROOM"IO_SLOT"
SEC"1"
SEC_TYPE"0402"
WATTAGE"1/16W"
VALUE"0.0"
TOLERANCE"5%"
LOCATION"R7E22"
MATERIAL"CHIP"
PACK_TYPE"0402"
PART_NUMBER"G21497-005";
"B"
$PN"2"65;
"A"
$PN"1"76;
%"RES"
"2","(2225,4300)","0","mstr_discrete","I343";
;
CDS_SEC"1"
CDS_LOCATION"R7E21"
CDS_LIB"mstr_discrete"
ROOM"IO_SLOT"
SEC"1"
SEC_TYPE"0402"
WATTAGE"1/16W"
MATERIAL"CHIP"
PACK_TYPE"0402"
TOLERANCE"1%"
VALUE"4.75K"
PART_NUMBER"G21796-072"
LOCATION"R7E21";
"A"
$PN"1"17;
"B"
$PN"2"76;
%"P3V3"
"1","(2225,4550)","0","mstr_symbols","I344";
;
HDL_POWER"P3V3"
BODY_TYPE"PLUMBING"
SIZE"1B"
CDS_LIB"mstr_symbols"
VOLTAGE"3.3V";
"G\NAC"17;
%"TAP"
"1","(1500,1875)","0","mstr_standard","I345";
;
HDL_TAP"TRUE"
BODY_TYPE"PLUMBING"
CDS_LIB"mstr_standard";
"B \NAC \NWC"4;
"S \NAC"
BN"8"19;
%"P12V"
"1","(-3275,925)","0","mstr_symbols","I4";
;
HDL_POWER"P12V"
BODY_TYPE"PLUMBING"
VOLTAGE"+12."
SIZE"1B"
CDS_LIB"mstr_symbols";
"G\NAC"18;
%"CAP_A"
"1","(-3275,1400)","0","dev_discrete","I5";
;
CDS_LOCATION"C2U21"
CDS_LIB"dev_discrete"
ROOM"IO_SLOT"
CDS_SEC"1"
SEC"1"
SEC_TYPE"0402V"
PACK_TYPE"0402V"
VALUE"0.1UF"
LOCATION"C2U21"
TOLERANCE"10%"
VOLTAGE"16V"
MATERIAL"X7R"
PART_NUMBER"A36096-030";
"B"
$PN"2"13;
"A"
$PN"1"12;
%"CAP_A"
"1","(-2875,1375)","0","dev_discrete","I7";
;
CDS_LIB"dev_discrete"
CDS_LOCATION"C2U25"
CDS_SEC"1"
ROOM"IO_SLOT"
SEC_TYPE"0402V"
SEC"1"
MATERIAL"X7R"
TOLERANCE"10%"
PACK_TYPE"0402V"
PART_NUMBER"A36096-030"
VALUE"0.1UF"
VOLTAGE"16V"
LOCATION"C2U25";
"B"
$PN"2"13;
"A"
$PN"1"12;
END.
